# T6G (Grand Teton) — schematic netlist excerpt (pin names and nets, part order shuffled) for the footprints in the layout excerpt that follows; sources: Cadence DE-HDL packaged netlist, KiCad conversion of 04192023_DAF0TMB3IC0_F0TG_MB_C_brd_V02_OCP.brd

R896  Q_RES  30K 1% EMPTY  pkg 0402LF  page 169 : A = P12V_AUX ; B = P3V3_AUX_DSC_VOL
L18  Q_INDUCTOR  BLM21SN300SN1D/5A IND  pkg SMLF  page 301 : \1\ = P1V8_CPU0_RT_1D ; \2\ = P1V8_CPU0_RT2_1A
R1744  Q_RES  10K 1% CHIP  pkg 0402LF  page 171 : A = P3V3_AUX ; B = JTAG_SCM_MUX_TDI

(kicad_pcb
	(version 20260206)
	(generator "pcbnew")
	(generator_version "10.0")
	(general
		(thickness 1.6)
		(legacy_teardrops no)
	)
	(paper "A4")
	(title_block
		(title "04192023_DAF0TMB3IC0_F0TG_MB_C_brd_V02_OCP.brd")
		(comment 1 "Grand Teton / footprints 3400-3402 of 8354")
	)
	(layers
		(0 "F.Cu" signal "TOP")
		(4 "In1.Cu" signal "GND")
		(6 "In2.Cu" signal "IN1")
		(8 "In3.Cu" signal "GND1")
		(10 "In4.Cu" signal "IN2")
		(12 "In5.Cu" signal "GND2")
		(14 "In6.Cu" signal "IN3")
		(16 "In7.Cu" signal "GND3")
		(18 "In8.Cu" signal "VCC")
		(20 "In9.Cu" signal "VCC1")
		(22 "In10.Cu" signal "GND4")
		(24 "In11.Cu" signal "IN4")
		(26 "In12.Cu" signal "GND5")
		(28 "In13.Cu" signal "IN5")
		(30 "In14.Cu" signal "GND6")
		(32 "In15.Cu" signal "IN6")
		(34 "In16.Cu" signal "GND7")
		(2 "B.Cu" signal "BOTTOM")
		(9 "F.Adhes" user "F.Adhesive")
		(11 "B.Adhes" user "B.Adhesive")
		(13 "F.Paste" user "Package Geometry/Pastemask Top")
		(15 "B.Paste" user "Package Geometry/Pastemask Bottom")
		(5 "F.SilkS" user "Ref Des/Silkscreen Top")
		(7 "B.SilkS" user "Ref Des/Silkscreen Bottom")
		(1 "F.Mask" user "Board Geometry/Soldermask Top")
		(3 "B.Mask" user "Board Geometry/Soldermask Bottom")
		(17 "Dwgs.User" user "User.Drawings")
		(19 "Cmts.User" user "User.Comments")
		(21 "Eco1.User" user "User.Eco1")
		(23 "Eco2.User" user "User.Eco2")
		(25 "Edge.Cuts" user "Board Geometry/Outline")
		(27 "Margin" user)
		(31 "F.CrtYd" user "Package Geometry/Place Bound Top")
		(29 "B.CrtYd" user "Package Geometry/Place Bound Bottom")
		(35 "F.Fab" user "Ref Des/Assembly Top")
		(33 "B.Fab" user "Ref Des/Assembly Bottom")
	)
	(footprint ""
		(layer "F.Cu")
		(at 46.70806 -99.60864 90)
		(property "Reference" "R896"
			(at 0 0 90)
			(layer "F.SilkS")
			(hide yes)
			(effects
				(font
					(size 1.27 1.27)
				)
			)
		)
		(property "Value" ""
			(at 0 0 90)
			(layer "F.Fab")
			(effects
				(font
					(size 1.27 1.27)
				)
			)
		)
		(duplicate_pad_numbers_are_jumpers no)
		(fp_line
			(start 0.7874 -0.4064)
			(end 0.7874 0.4064)
			(stroke
				(width 0.1524)
				(type default)
			)
			(layer "F.SilkS")
		)
		(fp_line
			(start -0.7874 -0.4064)
			(end 0.7874 -0.4064)
			(stroke
				(width 0.1524)
				(type default)
			)
			(layer "F.SilkS")
		)
		(fp_line
			(start 0.7874 0.4064)
			(end -0.7874 0.4064)
			(stroke
				(width 0.1524)
				(type default)
			)
			(layer "F.SilkS")
		)
		(fp_line
			(start -0.7874 0.4064)
			(end -0.7874 -0.4064)
			(stroke
				(width 0.1524)
				(type default)
			)
			(layer "F.SilkS")
		)
		(fp_line
			(start -0.12065 -0.305054)
			(end -0.12065 -0.2794)
			(stroke
				(width 0.1)
				(type default)
			)
			(layer "F.Fab")
		)
		(fp_line
			(start -0.67945 -0.305054)
			(end -0.12065 -0.305054)
			(stroke
				(width 0.1)
				(type default)
			)
			(layer "F.Fab")
		)
		(fp_line
			(start 0.67945 -0.3048)
			(end 0.67945 0.3048)
			(stroke
				(width 0.1)
				(type default)
			)
			(layer "F.Fab")
		)
		(fp_line
			(start 0.12065 -0.3048)
			(end 0.67945 -0.3048)
			(stroke
				(width 0.1)
				(type default)
			)
			(layer "F.Fab")
		)
		(fp_line
			(start 0.12065 -0.2794)
			(end 0.12065 -0.3048)
			(stroke
				(width 0.1)
				(type default)
			)
			(layer "F.Fab")
		)
		(fp_line
			(start -0.12065 -0.2794)
			(end 0.12065 -0.2794)
			(stroke
				(width 0.1)
				(type default)
			)
			(layer "F.Fab")
		)
		(fp_line
			(start 0.120396 0.2794)
			(end -0.12065 0.2794)
			(stroke
				(width 0.1)
				(type default)
			)
			(layer "F.Fab")
		)
		(fp_line
			(start -0.12065 0.2794)
			(end -0.12065 0.3048)
			(stroke
				(width 0.1)
				(type default)
			)
			(layer "F.Fab")
		)
		(fp_line
			(start 0.67945 0.3048)
			(end 0.120396 0.3048)
			(stroke
				(width 0.1)
				(type default)
			)
			(layer "F.Fab")
		)
		(fp_line
			(start 0.120396 0.3048)
			(end 0.120396 0.2794)
			(stroke
				(width 0.1)
				(type default)
			)
			(layer "F.Fab")
		)
		(fp_line
			(start -0.12065 0.3048)
			(end -0.67945 0.3048)
			(stroke
				(width 0.1)
				(type default)
			)
			(layer "F.Fab")
		)
		(fp_line
			(start -0.67945 0.3048)
			(end -0.67945 -0.305054)
			(stroke
				(width 0.1)
				(type default)
			)
			(layer "F.Fab")
		)
		(pad "1" smd circle
			(at -0.40005 0 90)
			(size 0 0)
			(layers "F.Cu" "F.Mask" "F.Paste")
			(net "P12V_AUX")
		)
		(pad "2" smd circle
			(at 0.40005 0 90)
			(size 0 0)
			(layers "F.Cu" "F.Mask" "F.Paste")
			(net "P3V3_AUX_DSC_VOL")
		)
	)
	(footprint ""
		(layer "F.Cu")
		(at 140.446252 -60.849764 180)
		(property "Reference" "R1744"
			(at 0 0 180)
			(layer "F.SilkS")
			(hide yes)
			(effects
				(font
					(size 1.27 1.27)
				)
			)
		)
		(property "Value" ""
			(at 0 0 180)
			(layer "F.Fab")
			(effects
				(font
					(size 1.27 1.27)
				)
			)
		)
		(duplicate_pad_numbers_are_jumpers no)
		(fp_line
			(start 0.7874 0.4064)
			(end -0.7874 0.4064)
			(stroke
				(width 0.1524)
				(type default)
			)
			(layer "F.SilkS")
		)
		(fp_line
			(start 0.7874 -0.4064)
			(end 0.7874 0.4064)
			(stroke
				(width 0.1524)
				(type default)
			)
			(layer "F.SilkS")
		)
		(fp_line
			(start -0.7874 0.4064)
			(end -0.7874 -0.4064)
			(stroke
				(width 0.1524)
				(type default)
			)
			(layer "F.SilkS")
		)
		(fp_line
			(start -0.7874 -0.4064)
			(end 0.7874 -0.4064)
			(stroke
				(width 0.1524)
				(type default)
			)
			(layer "F.SilkS")
		)
		(fp_line
			(start 0.67945 0.3048)
			(end 0.120396 0.3048)
			(stroke
				(width 0.1)
				(type default)
			)
			(layer "F.Fab")
		)
		(fp_line
			(start 0.67945 -0.3048)
			(end 0.67945 0.3048)
			(stroke
				(width 0.1)
				(type default)
			)
			(layer "F.Fab")
		)
		(fp_line
			(start 0.12065 -0.2794)
			(end 0.12065 -0.3048)
			(stroke
				(width 0.1)
				(type default)
			)
			(layer "F.Fab")
		)
		(fp_line
			(start 0.12065 -0.3048)
			(end 0.67945 -0.3048)
			(stroke
				(width 0.1)
				(type default)
			)
			(layer "F.Fab")
		)
		(fp_line
			(start 0.120396 0.3048)
			(end 0.120396 0.2794)
			(stroke
				(width 0.1)
				(type default)
			)
			(layer "F.Fab")
		)
		(fp_line
			(start 0.120396 0.2794)
			(end -0.12065 0.2794)
			(stroke
				(width 0.1)
				(type default)
			)
			(layer "F.Fab")
		)
		(fp_line
			(start -0.12065 0.3048)
			(end -0.67945 0.3048)
			(stroke
				(width 0.1)
				(type default)
			)
			(layer "F.Fab")
		)
		(fp_line
			(start -0.12065 0.2794)
			(end -0.12065 0.3048)
			(stroke
				(width 0.1)
				(type default)
			)
			(layer "F.Fab")
		)
		(fp_line
			(start -0.12065 -0.2794)
			(end 0.12065 -0.2794)
			(stroke
				(width 0.1)
				(type default)
			)
			(layer "F.Fab")
		)
		(fp_line
			(start -0.12065 -0.305054)
			(end -0.12065 -0.2794)
			(stroke
				(width 0.1)
				(type default)
			)
			(layer "F.Fab")
		)
		(fp_line
			(start -0.67945 0.3048)
			(end -0.67945 -0.305054)
			(stroke
				(width 0.1)
				(type default)
			)
			(layer "F.Fab")
		)
		(fp_line
			(start -0.67945 -0.305054)
			(end -0.12065 -0.305054)
			(stroke
				(width 0.1)
				(type default)
			)
			(layer "F.Fab")
		)
		(pad "1" smd circle
			(at -0.40005 0 180)
			(size 0 0)
			(layers "F.Cu" "F.Mask" "F.Paste")
			(net "P3V3_AUX")
		)
		(pad "2" smd circle
			(at 0.40005 0 180)
			(size 0 0)
			(layers "F.Cu" "F.Mask" "F.Paste")
			(net "JTAG_SCM_MUX_TDI")
		)
	)
	(footprint ""
		(layer "F.Cu")
		(at 426.332396 -392.9888 180)
		(property "Reference" "L18"
			(at 0 0 180)
			(layer "F.SilkS")
			(hide yes)
			(effects
				(font
					(size 1.27 1.27)
				)
			)
		)
		(property "Value" ""
			(at 0 0 180)
			(layer "F.Fab")
			(effects
				(font
					(size 1.27 1.27)
				)
			)
		)
		(duplicate_pad_numbers_are_jumpers no)
		(fp_line
			(start 1.63576 0.8128)
			(end -1.63576 0.8128)
			(stroke
				(width 0.1524)
				(type default)
			)
			(layer "F.SilkS")
		)
		(fp_line
			(start 1.63576 -0.8128)
			(end 1.63576 0.8128)
			(stroke
				(width 0.1524)
				(type default)
			)
			(layer "F.SilkS")
		)
		(fp_line
			(start -1.63576 -0.8128)
			(end 1.63576 -0.8128)
			(stroke
				(width 0.1524)
				(type default)
			)
			(layer "F.SilkS")
		)
		(fp_line
			(start -1.63576 -0.8128)
			(end -1.63576 0.8128)
			(stroke
				(width 0.1524)
				(type default)
			)
			(layer "F.SilkS")
		)
		(fp_line
			(start 1.560576 0.7366)
			(end 1.560576 -0.738632)
			(stroke
				(width 0.1)
				(type default)
			)
			(layer "F.Fab")
		)
		(fp_line
			(start 1.560576 -0.738632)
			(end -1.56083 -0.738632)
			(stroke
				(width 0.1)
				(type default)
			)
			(layer "F.Fab")
		)
		(fp_line
			(start 1.524 0.7366)
			(end 1.560576 0.7366)
			(stroke
				(width 0.1)
				(type default)
			)
			(layer "F.Fab")
		)
		(fp_line
			(start -1.524 0.7366)
			(end 1.524 0.7366)
			(stroke
				(width 0.1)
				(type default)
			)
			(layer "F.Fab")
		)
		(fp_line
			(start -1.56083 0.7366)
			(end -1.524 0.7366)
			(stroke
				(width 0.1)
				(type default)
			)
			(layer "F.Fab")
		)
		(fp_line
			(start -1.56083 -0.738632)
			(end -1.56083 0.7366)
			(stroke
				(width 0.1)
				(type default)
			)
			(layer "F.Fab")
		)
		(pad "1" smd rect
			(at -0.94996 0)
			(size 1.1176 1.3716)
			(layers "F.Cu" "F.Mask" "F.Paste")
			(net "P1V8_CPU0_RT_1D")
		)
		(pad "2" smd rect
			(at 0.94996 0)
			(size 1.1176 1.3716)
			(layers "F.Cu" "F.Mask" "F.Paste")
			(net "P1V8_CPU0_RT2_1A")
		)
	)
)
